# T6G (Grand Teton) — schematic netlist excerpt (pin names and nets, part order shuffled) for the footprints in the layout excerpt that follows; sources: Cadence DE-HDL packaged netlist, KiCad conversion of 04192023_DAF0TMB3IC0_F0TG_MB_C_brd_V02_OCP.brd

C519  Q_CAP  0.1UF 10V 10% X7S  pkg C0201  page 279 : A = P1V8_CPU0_RT0_1A ; B = GND
PC334_1  Q_CAP  22UF 16V 20% X6S  pkg C0805  page 215 : A = SW_P12V_AUX_PVDDCR_SOC_P1_FLT ; B = GND
PC126_3  Q_CAP  22UF 16V 20% X6S  pkg C0805  page 202 : A = SW_P12V_AUX_PVDDCR_CPU1_P0_FLT ; B = GND
R1255  Q_RES  0 5% CHIP  pkg 0402LF  page 258 : A = PVDD_33_S5_ADC ; B = PVDD_33_S5_ADC_TIC

(kicad_pcb
	(version 20260206)
	(generator "pcbnew")
	(generator_version "10.0")
	(general
		(thickness 1.6)
		(legacy_teardrops no)
	)
	(paper "A4")
	(title_block
		(title "04192023_DAF0TMB3IC0_F0TG_MB_C_brd_V02_OCP.brd")
		(comment 1 "Grand Teton / footprints 6629-6632 of 8354")
	)
	(layers
		(0 "F.Cu" signal "TOP")
		(4 "In1.Cu" signal "GND")
		(6 "In2.Cu" signal "IN1")
		(8 "In3.Cu" signal "GND1")
		(10 "In4.Cu" signal "IN2")
		(12 "In5.Cu" signal "GND2")
		(14 "In6.Cu" signal "IN3")
		(16 "In7.Cu" signal "GND3")
		(18 "In8.Cu" signal "VCC")
		(20 "In9.Cu" signal "VCC1")
		(22 "In10.Cu" signal "GND4")
		(24 "In11.Cu" signal "IN4")
		(26 "In12.Cu" signal "GND5")
		(28 "In13.Cu" signal "IN5")
		(30 "In14.Cu" signal "GND6")
		(32 "In15.Cu" signal "IN6")
		(34 "In16.Cu" signal "GND7")
		(2 "B.Cu" signal "BOTTOM")
		(9 "F.Adhes" user "F.Adhesive")
		(11 "B.Adhes" user "B.Adhesive")
		(13 "F.Paste" user "Package Geometry/Pastemask Top")
		(15 "B.Paste" user "Package Geometry/Pastemask Bottom")
		(5 "F.SilkS" user "Ref Des/Silkscreen Top")
		(7 "B.SilkS" user "Ref Des/Silkscreen Bottom")
		(1 "F.Mask" user "Board Geometry/Soldermask Top")
		(3 "B.Mask" user "Board Geometry/Soldermask Bottom")
		(17 "Dwgs.User" user "User.Drawings")
		(19 "Cmts.User" user "User.Comments")
		(21 "Eco1.User" user "User.Eco1")
		(23 "Eco2.User" user "User.Eco2")
		(25 "Edge.Cuts" user "Board Geometry/Outline")
		(27 "Margin" user)
		(31 "F.CrtYd" user "Package Geometry/Place Bound Top")
		(29 "B.CrtYd" user "Package Geometry/Place Bound Bottom")
		(35 "F.Fab" user "Ref Des/Assembly Top")
		(33 "B.Fab" user "Ref Des/Assembly Bottom")
	)
	(footprint ""
		(layer "B.Cu")
		(at 313.118246 -396.393162 -90)
		(property "Reference" "C519"
			(at 0 0 90)
			(layer "B.SilkS")
			(hide yes)
			(effects
				(font
					(size 1.27 1.27)
				)
				(justify mirror)
			)
		)
		(property "Value" ""
			(at 0 0 90)
			(layer "B.Fab")
			(effects
				(font
					(size 1.27 1.27)
				)
				(justify mirror)
			)
		)
		(duplicate_pad_numbers_are_jumpers no)
		(fp_line
			(start -0.299974 0.150114)
			(end 0.299974 0.150114)
			(stroke
				(width 0.1)
				(type default)
			)
			(layer "B.Fab")
		)
		(fp_line
			(start 0.299974 0.150114)
			(end 0.299974 -0.150114)
			(stroke
				(width 0.1)
				(type default)
			)
			(layer "B.Fab")
		)
		(fp_line
			(start -0.299974 -0.150114)
			(end -0.299974 0.150114)
			(stroke
				(width 0.1)
				(type default)
			)
			(layer "B.Fab")
		)
		(fp_line
			(start 0.299974 -0.150114)
			(end -0.299974 -0.150114)
			(stroke
				(width 0.1)
				(type default)
			)
			(layer "B.Fab")
		)
		(pad "1" smd rect
			(at 0.2667 0 90)
			(size 0.3048 0.381)
			(layers "B.Cu" "B.Mask" "B.Paste")
			(net "P1V8_CPU0_RT0_1A")
		)
		(pad "2" smd rect
			(at -0.2667 0 90)
			(size 0.3048 0.381)
			(layers "B.Cu" "B.Mask" "B.Paste")
			(net "GND")
		)
	)
	(footprint ""
		(layer "B.Cu")
		(at 319.467484 -338.934806 -90)
		(property "Reference" "PC126_3"
			(at 0 0 90)
			(layer "B.SilkS")
			(hide yes)
			(effects
				(font
					(size 1.27 1.27)
				)
				(justify mirror)
			)
		)
		(property "Value" ""
			(at 0 0 90)
			(layer "B.Fab")
			(effects
				(font
					(size 1.27 1.27)
				)
				(justify mirror)
			)
		)
		(duplicate_pad_numbers_are_jumpers no)
		(fp_line
			(start -1.524 0.762)
			(end 1.524 0.762)
			(stroke
				(width 0.1524)
				(type default)
			)
			(layer "B.SilkS")
		)
		(fp_line
			(start 1.524 0.762)
			(end 1.524 -0.762)
			(stroke
				(width 0.1524)
				(type default)
			)
			(layer "B.SilkS")
		)
		(fp_line
			(start -1.524 -0.762)
			(end -1.524 0.762)
			(stroke
				(width 0.1524)
				(type default)
			)
			(layer "B.SilkS")
		)
		(fp_line
			(start 1.524 -0.762)
			(end -1.524 -0.762)
			(stroke
				(width 0.1524)
				(type default)
			)
			(layer "B.SilkS")
		)
		(fp_line
			(start -1.1049 0.724916)
			(end -1.1049 -0.724916)
			(stroke
				(width 0.1)
				(type default)
			)
			(layer "B.Fab")
		)
		(fp_line
			(start 1.1049 0.724916)
			(end -1.1049 0.724916)
			(stroke
				(width 0.1)
				(type default)
			)
			(layer "B.Fab")
		)
		(fp_line
			(start -1.1049 -0.724916)
			(end 1.1049 -0.724916)
			(stroke
				(width 0.1)
				(type default)
			)
			(layer "B.Fab")
		)
		(fp_line
			(start 1.1049 -0.724916)
			(end 1.1049 0.724916)
			(stroke
				(width 0.1)
				(type default)
			)
			(layer "B.Fab")
		)
		(pad "1" smd rect
			(at 0.889 0 270)
			(size 1.016 1.27)
			(layers "B.Cu" "B.Mask" "B.Paste")
			(net "SW_P12V_AUX_PVDDCR_CPU1_P0_FLT")
		)
		(pad "2" smd rect
			(at -0.889 0 270)
			(size 1.016 1.27)
			(layers "B.Cu" "B.Mask" "B.Paste")
			(net "GND")
		)
	)
	(footprint ""
		(layer "B.Cu")
		(at 110.808008 -171.775374 -90)
		(property "Reference" "PC334_1"
			(at 0 0 90)
			(layer "B.SilkS")
			(hide yes)
			(effects
				(font
					(size 1.27 1.27)
				)
				(justify mirror)
			)
		)
		(property "Value" ""
			(at 0 0 90)
			(layer "B.Fab")
			(effects
				(font
					(size 1.27 1.27)
				)
				(justify mirror)
			)
		)
		(duplicate_pad_numbers_are_jumpers no)
		(fp_line
			(start -1.524 0.762)
			(end 1.524 0.762)
			(stroke
				(width 0.1524)
				(type default)
			)
			(layer "B.SilkS")
		)
		(fp_line
			(start 1.524 0.762)
			(end 1.524 -0.762)
			(stroke
				(width 0.1524)
				(type default)
			)
			(layer "B.SilkS")
		)
		(fp_line
			(start -1.524 -0.762)
			(end -1.524 0.762)
			(stroke
				(width 0.1524)
				(type default)
			)
			(layer "B.SilkS")
		)
		(fp_line
			(start 1.524 -0.762)
			(end -1.524 -0.762)
			(stroke
				(width 0.1524)
				(type default)
			)
			(layer "B.SilkS")
		)
		(fp_line
			(start -1.1049 0.724916)
			(end -1.1049 -0.724916)
			(stroke
				(width 0.1)
				(type default)
			)
			(layer "B.Fab")
		)
		(fp_line
			(start 1.1049 0.724916)
			(end -1.1049 0.724916)
			(stroke
				(width 0.1)
				(type default)
			)
			(layer "B.Fab")
		)
		(fp_line
			(start -1.1049 -0.724916)
			(end 1.1049 -0.724916)
			(stroke
				(width 0.1)
				(type default)
			)
			(layer "B.Fab")
		)
		(fp_line
			(start 1.1049 -0.724916)
			(end 1.1049 0.724916)
			(stroke
				(width 0.1)
				(type default)
			)
			(layer "B.Fab")
		)
		(pad "1" smd rect
			(at 0.889 0 270)
			(size 1.016 1.27)
			(layers "B.Cu" "B.Mask" "B.Paste")
			(net "SW_P12V_AUX_PVDDCR_SOC_P1_FLT")
		)
		(pad "2" smd rect
			(at -0.889 0 270)
			(size 1.016 1.27)
			(layers "B.Cu" "B.Mask" "B.Paste")
			(net "GND")
		)
	)
	(footprint ""
		(layer "B.Cu")
		(at 231.0511 -327.21169)
		(property "Reference" "R1255"
			(at 0 0 0)
			(layer "B.SilkS")
			(hide yes)
			(effects
				(font
					(size 1.27 1.27)
				)
				(justify mirror)
			)
		)
		(property "Value" ""
			(at 0 0 0)
			(layer "B.Fab")
			(effects
				(font
					(size 1.27 1.27)
				)
				(justify mirror)
			)
		)
		(duplicate_pad_numbers_are_jumpers no)
		(fp_line
			(start -0.7874 -0.4064)
			(end -0.7874 0.4064)
			(stroke
				(width 0.1524)
				(type default)
			)
			(layer "B.SilkS")
		)
		(fp_line
			(start -0.7874 0.4064)
			(end 0.7874 0.4064)
			(stroke
				(width 0.1524)
				(type default)
			)
			(layer "B.SilkS")
		)
		(fp_line
			(start 0.7874 -0.4064)
			(end -0.7874 -0.4064)
			(stroke
				(width 0.1524)
				(type default)
			)
			(layer "B.SilkS")
		)
		(fp_line
			(start 0.7874 0.4064)
			(end 0.7874 -0.4064)
			(stroke
				(width 0.1524)
				(type default)
			)
			(layer "B.SilkS")
		)
		(fp_line
			(start -0.67945 -0.3048)
			(end -0.67945 0.3048)
			(stroke
				(width 0.1)
				(type default)
			)
			(layer "B.Fab")
		)
		(fp_line
			(start -0.67945 0.3048)
			(end -0.120396 0.3048)
			(stroke
				(width 0.1)
				(type default)
			)
			(layer "B.Fab")
		)
		(fp_line
			(start -0.12065 -0.3048)
			(end -0.67945 -0.3048)
			(stroke
				(width 0.1)
				(type default)
			)
			(layer "B.Fab")
		)
		(fp_line
			(start -0.12065 -0.2794)
			(end -0.12065 -0.3048)
			(stroke
				(width 0.1)
				(type default)
			)
			(layer "B.Fab")
		)
		(fp_line
			(start -0.120396 0.2794)
			(end 0.12065 0.2794)
			(stroke
				(width 0.1)
				(type default)
			)
			(layer "B.Fab")
		)
		(fp_line
			(start -0.120396 0.3048)
			(end -0.120396 0.2794)
			(stroke
				(width 0.1)
				(type default)
			)
			(layer "B.Fab")
		)
		(fp_line
			(start 0.12065 -0.305054)
			(end 0.12065 -0.2794)
			(stroke
				(width 0.1)
				(type default)
			)
			(layer "B.Fab")
		)
		(fp_line
			(start 0.12065 -0.2794)
			(end -0.12065 -0.2794)
			(stroke
				(width 0.1)
				(type default)
			)
			(layer "B.Fab")
		)
		(fp_line
			(start 0.12065 0.2794)
			(end 0.12065 0.3048)
			(stroke
				(width 0.1)
				(type default)
			)
			(layer "B.Fab")
		)
		(fp_line
			(start 0.12065 0.3048)
			(end 0.67945 0.3048)
			(stroke
				(width 0.1)
				(type default)
			)
			(layer "B.Fab")
		)
		(fp_line
			(start 0.67945 -0.305054)
			(end 0.12065 -0.305054)
			(stroke
				(width 0.1)
				(type default)
			)
			(layer "B.Fab")
		)
		(fp_line
			(start 0.67945 0.3048)
			(end 0.67945 -0.305054)
			(stroke
				(width 0.1)
				(type default)
			)
			(layer "B.Fab")
		)
		(pad "1" smd rect
			(at 0.40005 0)
			(size 0.4572 0.508)
			(layers "B.Cu" "B.Mask" "B.Paste")
			(net "PVDD_33_S5_ADC")
		)
		(pad "2" smd rect
			(at -0.40005 0)
			(size 0.4572 0.508)
			(layers "B.Cu" "B.Mask" "B.Paste")
			(net "PVDD_33_S5_ADC_TIC")
		)
	)
)
